(kicad_pcb
	(version 20260206)
	(generator "pcbnew")
	(generator_version "10.0")
	(general
		(thickness 1.6)
		(legacy_teardrops no)
	)
	(paper "A4")
	(title_block
		(title "03242023_DA0F0TMBIJ0_F0T_Motherboard_J_brd_V01_OCP.brd")
		(comment 1 "Grand Teton / footprints 1839-1843 of 6105")
	)
	(layers
		(0 "F.Cu" signal "TOP")
		(4 "In1.Cu" signal "GND")
		(6 "In2.Cu" signal "IN1")
		(8 "In3.Cu" signal "GND1")
		(10 "In4.Cu" signal "IN2")
		(12 "In5.Cu" signal "GND2")
		(14 "In6.Cu" signal "IN3")
		(16 "In7.Cu" signal "GND3")
		(18 "In8.Cu" signal "VCC")
		(20 "In9.Cu" signal "VCC1")
		(22 "In10.Cu" signal "GND4")
		(24 "In11.Cu" signal "IN4")
		(26 "In12.Cu" signal "GND5")
		(28 "In13.Cu" signal "IN5")
		(30 "In14.Cu" signal "GND6")
		(32 "In15.Cu" signal "IN6")
		(34 "In16.Cu" signal "GND7")
		(2 "B.Cu" signal "BOTTOM")
		(9 "F.Adhes" user "F.Adhesive")
		(11 "B.Adhes" user "B.Adhesive")
		(13 "F.Paste" user "Package Geometry/Pastemask Top")
		(15 "B.Paste" user "Package Geometry/Pastemask Bottom")
		(5 "F.SilkS" user "Ref Des/Silkscreen Top")
		(7 "B.SilkS" user "Ref Des/Silkscreen Bottom")
		(1 "F.Mask" user "Board Geometry/Soldermask Top")
		(3 "B.Mask" user "Board Geometry/Soldermask Bottom")
		(17 "Dwgs.User" user "User.Drawings")
		(19 "Cmts.User" user "User.Comments")
		(21 "Eco1.User" user "User.Eco1")
		(23 "Eco2.User" user "User.Eco2")
		(25 "Edge.Cuts" user "Board Geometry/Outline")
		(27 "Margin" user)
		(31 "F.CrtYd" user "Package Geometry/Place Bound Top")
		(29 "B.CrtYd" user "Package Geometry/Place Bound Bottom")
		(35 "F.Fab" user "Ref Des/Assembly Top")
		(33 "B.Fab" user "Ref Des/Assembly Bottom")
	)
	(footprint ""
		(layer "F.Cu")
		(at 211.76361 -57.548272 -90)
		(property "Reference" "R3763"
			(at 0 0 270)
			(layer "F.SilkS")
			(hide yes)
			(effects
				(font
					(size 1.27 1.27)
				)
			)
		)
		(property "Value" ""
			(at 0 0 270)
			(layer "F.Fab")
			(effects
				(font
					(size 1.27 1.27)
				)
			)
		)
		(duplicate_pad_numbers_are_jumpers no)
		(fp_line
			(start -0.7874 0.4064)
			(end -0.7874 -0.4064)
			(stroke
				(width 0.1524)
				(type default)
			)
			(layer "F.SilkS")
		)
		(fp_line
			(start 0.7874 0.4064)
			(end -0.7874 0.4064)
			(stroke
				(width 0.1524)
				(type default)
			)
			(layer "F.SilkS")
		)
		(fp_line
			(start -0.7874 -0.4064)
			(end 0.7874 -0.4064)
			(stroke
				(width 0.1524)
				(type default)
			)
			(layer "F.SilkS")
		)
		(fp_line
			(start 0.7874 -0.4064)
			(end 0.7874 0.4064)
			(stroke
				(width 0.1524)
				(type default)
			)
			(layer "F.SilkS")
		)
		(fp_line
			(start -0.67945 0.3048)
			(end -0.67945 -0.305054)
			(stroke
				(width 0.1)
				(type default)
			)
			(layer "F.Fab")
		)
		(fp_line
			(start -0.12065 0.3048)
			(end -0.67945 0.3048)
			(stroke
				(width 0.1)
				(type default)
			)
			(layer "F.Fab")
		)
		(fp_line
			(start 0.120396 0.3048)
			(end 0.120396 0.2794)
			(stroke
				(width 0.1)
				(type default)
			)
			(layer "F.Fab")
		)
		(fp_line
			(start 0.67945 0.3048)
			(end 0.120396 0.3048)
			(stroke
				(width 0.1)
				(type default)
			)
			(layer "F.Fab")
		)
		(fp_line
			(start -0.12065 0.2794)
			(end -0.12065 0.3048)
			(stroke
				(width 0.1)
				(type default)
			)
			(layer "F.Fab")
		)
		(fp_line
			(start 0.120396 0.2794)
			(end -0.12065 0.2794)
			(stroke
				(width 0.1)
				(type default)
			)
			(layer "F.Fab")
		)
		(fp_line
			(start -0.12065 -0.2794)
			(end 0.12065 -0.2794)
			(stroke
				(width 0.1)
				(type default)
			)
			(layer "F.Fab")
		)
		(fp_line
			(start 0.12065 -0.2794)
			(end 0.12065 -0.3048)
			(stroke
				(width 0.1)
				(type default)
			)
			(layer "F.Fab")
		)
		(fp_line
			(start 0.12065 -0.3048)
			(end 0.67945 -0.3048)
			(stroke
				(width 0.1)
				(type default)
			)
			(layer "F.Fab")
		)
		(fp_line
			(start 0.67945 -0.3048)
			(end 0.67945 0.3048)
			(stroke
				(width 0.1)
				(type default)
			)
			(layer "F.Fab")
		)
		(fp_line
			(start -0.67945 -0.305054)
			(end -0.12065 -0.305054)
			(stroke
				(width 0.1)
				(type default)
			)
			(layer "F.Fab")
		)
		(fp_line
			(start -0.12065 -0.305054)
			(end -0.12065 -0.2794)
			(stroke
				(width 0.1)
				(type default)
			)
			(layer "F.Fab")
		)
		(pad "1" smd circle
			(at -0.40005 0 270)
			(size 0 0)
			(layers "F.Cu" "F.Mask" "F.Paste")
			(net "GND")
		)
		(pad "2" smd circle
			(at 0.40005 0 270)
			(size 0 0)
			(layers "F.Cu" "F.Mask" "F.Paste")
			(net "INA230_2_A1")
		)
	)
	(footprint ""
		(layer "F.Cu")
		(at 435.142386 -175.20285 90)
		(property "Reference" "PR4698"
			(at 0 0 90)
			(layer "F.SilkS")
			(hide yes)
			(effects
				(font
					(size 1.27 1.27)
				)
			)
		)
		(property "Value" ""
			(at 0 0 90)
			(layer "F.Fab")
			(effects
				(font
					(size 1.27 1.27)
				)
			)
		)
		(duplicate_pad_numbers_are_jumpers no)
		(fp_line
			(start 0.7874 -0.4064)
			(end 0.7874 0.4064)
			(stroke
				(width 0.1524)
				(type default)
			)
			(layer "F.SilkS")
		)
		(fp_line
			(start -0.7874 -0.4064)
			(end 0.7874 -0.4064)
			(stroke
				(width 0.1524)
				(type default)
			)
			(layer "F.SilkS")
		)
		(fp_line
			(start 0.7874 0.4064)
			(end -0.7874 0.4064)
			(stroke
				(width 0.1524)
				(type default)
			)
			(layer "F.SilkS")
		)
		(fp_line
			(start -0.7874 0.4064)
			(end -0.7874 -0.4064)
			(stroke
				(width 0.1524)
				(type default)
			)
			(layer "F.SilkS")
		)
		(fp_line
			(start -0.12065 -0.305054)
			(end -0.12065 -0.2794)
			(stroke
				(width 0.1)
				(type default)
			)
			(layer "F.Fab")
		)
		(fp_line
			(start -0.67945 -0.305054)
			(end -0.12065 -0.305054)
			(stroke
				(width 0.1)
				(type default)
			)
			(layer "F.Fab")
		)
		(fp_line
			(start 0.67945 -0.3048)
			(end 0.67945 0.3048)
			(stroke
				(width 0.1)
				(type default)
			)
			(layer "F.Fab")
		)
		(fp_line
			(start 0.12065 -0.3048)
			(end 0.67945 -0.3048)
			(stroke
				(width 0.1)
				(type default)
			)
			(layer "F.Fab")
		)
		(fp_line
			(start 0.12065 -0.2794)
			(end 0.12065 -0.3048)
			(stroke
				(width 0.1)
				(type default)
			)
			(layer "F.Fab")
		)
		(fp_line
			(start -0.12065 -0.2794)
			(end 0.12065 -0.2794)
			(stroke
				(width 0.1)
				(type default)
			)
			(layer "F.Fab")
		)
		(fp_line
			(start 0.120396 0.2794)
			(end -0.12065 0.2794)
			(stroke
				(width 0.1)
				(type default)
			)
			(layer "F.Fab")
		)
		(fp_line
			(start -0.12065 0.2794)
			(end -0.12065 0.3048)
			(stroke
				(width 0.1)
				(type default)
			)
			(layer "F.Fab")
		)
		(fp_line
			(start 0.67945 0.3048)
			(end 0.120396 0.3048)
			(stroke
				(width 0.1)
				(type default)
			)
			(layer "F.Fab")
		)
		(fp_line
			(start 0.120396 0.3048)
			(end 0.120396 0.2794)
			(stroke
				(width 0.1)
				(type default)
			)
			(layer "F.Fab")
		)
		(fp_line
			(start -0.12065 0.3048)
			(end -0.67945 0.3048)
			(stroke
				(width 0.1)
				(type default)
			)
			(layer "F.Fab")
		)
		(fp_line
			(start -0.67945 0.3048)
			(end -0.67945 -0.305054)
			(stroke
				(width 0.1)
				(type default)
			)
			(layer "F.Fab")
		)
		(pad "1" smd circle
			(at -0.40005 0 90)
			(size 0 0)
			(layers "F.Cu" "F.Mask" "F.Paste")
			(net "PVNN_MAIN_CPU0_FB_RC")
		)
		(pad "2" smd circle
			(at 0.40005 0 90)
			(size 0 0)
			(layers "F.Cu" "F.Mask" "F.Paste")
			(net "PVNN_MAIN_CPU0")
		)
	)
	(footprint ""
		(layer "F.Cu")
		(at 51.593496 -117.53977)
		(property "Reference" "R3706"
			(at 0 0 0)
			(layer "F.SilkS")
			(hide yes)
			(effects
				(font
					(size 1.27 1.27)
				)
			)
		)
		(property "Value" ""
			(at 0 0 0)
			(layer "F.Fab")
			(effects
				(font
					(size 1.27 1.27)
				)
			)
		)
		(duplicate_pad_numbers_are_jumpers no)
		(fp_line
			(start -0.7874 -0.4064)
			(end 0.7874 -0.4064)
			(stroke
				(width 0.1524)
				(type default)
			)
			(layer "F.SilkS")
		)
		(fp_line
			(start -0.7874 0.4064)
			(end -0.7874 -0.4064)
			(stroke
				(width 0.1524)
				(type default)
			)
			(layer "F.SilkS")
		)
		(fp_line
			(start 0.7874 -0.4064)
			(end 0.7874 0.4064)
			(stroke
				(width 0.1524)
				(type default)
			)
			(layer "F.SilkS")
		)
		(fp_line
			(start 0.7874 0.4064)
			(end -0.7874 0.4064)
			(stroke
				(width 0.1524)
				(type default)
			)
			(layer "F.SilkS")
		)
		(fp_line
			(start -0.67945 -0.305054)
			(end -0.12065 -0.305054)
			(stroke
				(width 0.1)
				(type default)
			)
			(layer "F.Fab")
		)
		(fp_line
			(start -0.67945 0.3048)
			(end -0.67945 -0.305054)
			(stroke
				(width 0.1)
				(type default)
			)
			(layer "F.Fab")
		)
		(fp_line
			(start -0.12065 -0.305054)
			(end -0.12065 -0.2794)
			(stroke
				(width 0.1)
				(type default)
			)
			(layer "F.Fab")
		)
		(fp_line
			(start -0.12065 -0.2794)
			(end 0.12065 -0.2794)
			(stroke
				(width 0.1)
				(type default)
			)
			(layer "F.Fab")
		)
		(fp_line
			(start -0.12065 0.2794)
			(end -0.12065 0.3048)
			(stroke
				(width 0.1)
				(type default)
			)
			(layer "F.Fab")
		)
		(fp_line
			(start -0.12065 0.3048)
			(end -0.67945 0.3048)
			(stroke
				(width 0.1)
				(type default)
			)
			(layer "F.Fab")
		)
		(fp_line
			(start 0.120396 0.2794)
			(end -0.12065 0.2794)
			(stroke
				(width 0.1)
				(type default)
			)
			(layer "F.Fab")
		)
		(fp_line
			(start 0.120396 0.3048)
			(end 0.120396 0.2794)
			(stroke
				(width 0.1)
				(type default)
			)
			(layer "F.Fab")
		)
		(fp_line
			(start 0.12065 -0.3048)
			(end 0.67945 -0.3048)
			(stroke
				(width 0.1)
				(type default)
			)
			(layer "F.Fab")
		)
		(fp_line
			(start 0.12065 -0.2794)
			(end 0.12065 -0.3048)
			(stroke
				(width 0.1)
				(type default)
			)
			(layer "F.Fab")
		)
		(fp_line
			(start 0.67945 -0.3048)
			(end 0.67945 0.3048)
			(stroke
				(width 0.1)
				(type default)
			)
			(layer "F.Fab")
		)
		(fp_line
			(start 0.67945 0.3048)
			(end 0.120396 0.3048)
			(stroke
				(width 0.1)
				(type default)
			)
			(layer "F.Fab")
		)
		(pad "1" smd circle
			(at -0.40005 0)
			(size 0 0)
			(layers "F.Cu" "F.Mask" "F.Paste")
			(net "P3V3_AUX")
		)
		(pad "2" smd circle
			(at 0.40005 0)
			(size 0 0)
			(layers "F.Cu" "F.Mask" "F.Paste")
			(net "PCA9548_PCIE0_ADDR1")
		)
	)
	(footprint ""
		(layer "F.Cu")
		(at 84.181696 -70.78599)
		(property "Reference" "D90"
			(at -43.164506 50.178462 90)
			(unlocked yes)
			(layer "F.SilkS")
			(effects
				(font
					(size 0.635 0.4064)
					(thickness 0.1524)
				)
				(justify left)
			)
		)
		(property "Value" ""
			(at 0 0 0)
			(layer "F.Fab")
			(effects
				(font
					(size 1.27 1.27)
				)
			)
		)
		(duplicate_pad_numbers_are_jumpers no)
		(fp_line
			(start -0.90678 0.4826)
			(end -0.90678 -0.4699)
			(stroke
				(width 0.1524)
				(type default)
			)
			(layer "F.SilkS")
		)
		(fp_line
			(start -0.89408 -0.4826)
			(end 0.90678 -0.4826)
			(stroke
				(width 0.1524)
				(type default)
			)
			(layer "F.SilkS")
		)
		(fp_line
			(start -0.79248 -0.4826)
			(end 1.03378 -0.4826)
			(stroke
				(width 0.1524)
				(type default)
			)
			(layer "F.SilkS")
		)
		(fp_line
			(start -0.64008 -0.4826)
			(end 1.16078 -0.4826)
			(stroke
				(width 0.1524)
				(type default)
			)
			(layer "F.SilkS")
		)
		(fp_line
			(start 0.90678 -0.4826)
			(end 0.90678 0.4826)
			(stroke
				(width 0.1524)
				(type default)
			)
			(layer "F.SilkS")
		)
		(fp_line
			(start 0.90678 0.4826)
			(end -0.90678 0.4826)
			(stroke
				(width 0.1524)
				(type default)
			)
			(layer "F.SilkS")
		)
		(fp_line
			(start 1.03378 -0.4826)
			(end 1.03378 0.4826)
			(stroke
				(width 0.1524)
				(type default)
			)
			(layer "F.SilkS")
		)
		(fp_line
			(start 1.03378 0.4826)
			(end -0.79248 0.4826)
			(stroke
				(width 0.1524)
				(type default)
			)
			(layer "F.SilkS")
		)
		(fp_line
			(start 1.16078 -0.4826)
			(end 1.16078 0.4826)
			(stroke
				(width 0.1524)
				(type default)
			)
			(layer "F.SilkS")
		)
		(fp_line
			(start 1.16078 0.4826)
			(end -0.64008 0.4826)
			(stroke
				(width 0.1524)
				(type default)
			)
			(layer "F.SilkS")
		)
		(fp_line
			(start -0.499872 -0.249936)
			(end 0.499872 -0.249936)
			(stroke
				(width 0.1)
				(type default)
			)
			(layer "F.Fab")
		)
		(fp_line
			(start -0.499872 0.249936)
			(end -0.499872 -0.249936)
			(stroke
				(width 0.1)
				(type default)
			)
			(layer "F.Fab")
		)
		(fp_line
			(start 0.499872 -0.249936)
			(end 0.499872 0.249936)
			(stroke
				(width 0.1)
				(type default)
			)
			(layer "F.Fab")
		)
		(fp_line
			(start 0.499872 0.249936)
			(end -0.499872 0.249936)
			(stroke
				(width 0.1)
				(type default)
			)
			(layer "F.Fab")
		)
		(pad "A" smd rect
			(at -0.47498 0)
			(size 0.6096 0.7112)
			(layers "F.Cu" "F.Mask" "F.Paste")
			(net "LED_RST_PLTRST_N")
		)
		(pad "C" smd rect
			(at 0.47498 0)
			(size 0.6096 0.7112)
			(layers "F.Cu" "F.Mask" "F.Paste")
			(net "LED_RST_PLTRST_N_D")
		)
	)
	(footprint ""
		(layer "F.Cu")
		(at 416.009582 -162.185858 -90)
		(property "Reference" "PU36"
			(at -1.68148 -6.204458 0)
			(unlocked yes)
			(layer "F.SilkS")
			(effects
				(font
					(size 0.7874 0.5842)
					(thickness 0.1524)
				)
				(justify left)
			)
		)
		(property "Value" ""
			(at 0 0 270)
			(layer "F.Fab")
			(effects
				(font
					(size 1.27 1.27)
				)
			)
		)
		(duplicate_pad_numbers_are_jumpers no)
		(fp_line
			(start -2.500122 2.999994)
			(end -2.500122 2.339594)
			(stroke
				(width 0.1524)
				(type default)
			)
			(layer "F.SilkS")
		)
		(fp_line
			(start -2.2987 2.999994)
			(end -2.500122 2.999994)
			(stroke
				(width 0.1524)
				(type default)
			)
			(layer "F.SilkS")
		)
		(fp_line
			(start 2.500122 2.999994)
			(end 2.2987 2.999994)
			(stroke
				(width 0.1524)
				(type default)
			)
			(layer "F.SilkS")
		)
		(fp_line
			(start 2.500122 2.339594)
			(end 2.500122 2.999994)
			(stroke
				(width 0.1524)
				(type default)
			)
			(layer "F.SilkS")
		)
		(fp_line
			(start -2.500122 0.6604)
			(end -2.500122 0.229108)
			(stroke
				(width 0.1524)
				(type default)
			)
			(layer "F.SilkS")
		)
		(fp_line
			(start -2.500122 -2.529078)
			(end -2.500122 -2.999994)
			(stroke
				(width 0.1524)
				(type default)
			)
			(layer "F.SilkS")
		)
		(fp_line
			(start -2.500122 -2.999994)
			(end -2.24409 -2.999994)
			(stroke
				(width 0.1524)
				(type default)
			)
			(layer "F.SilkS")
		)
		(fp_line
			(start 2.31394 -2.999994)
			(end 2.500122 -2.999994)
			(stroke
				(width 0.1524)
				(type default)
			)
			(layer "F.SilkS")
		)
		(fp_line
			(start 2.500122 -2.999994)
			(end 2.500122 -2.44348)
			(stroke
				(width 0.1524)
				(type default)
			)
			(layer "F.SilkS")
		)
		(fp_poly
			(pts
				(xy -4.253992 -2.254758) (xy -5.269992 -1.746758) (xy -5.269992 -2.762758)
			)
			(stroke
				(width 0)
				(type default)
			)
			(fill yes)
			(layer "F.SilkS")
		)
		(fp_line
			(start -2.500122 2.999994)
			(end -2.500122 -2.999994)
			(stroke
				(width 0.1)
				(type default)
			)
			(layer "F.Fab")
		)
		(fp_line
			(start 2.500122 2.999994)
			(end -2.500122 2.999994)
			(stroke
				(width 0.1)
				(type default)
			)
			(layer "F.Fab")
		)
		(fp_line
			(start -2.500122 -2.999994)
			(end 2.500122 -2.999994)
			(stroke
				(width 0.1)
				(type default)
			)
			(layer "F.Fab")
		)
		(fp_line
			(start 2.500122 -2.999994)
			(end 2.500122 2.999994)
			(stroke
				(width 0.1)
				(type default)
			)
			(layer "F.Fab")
		)
		(fp_poly
			(pts
				(xy -4.218432 -2.783078) (xy -4.218432 -1.767078) (xy -3.202432 -2.275078)
			)
			(stroke
				(width 0)
				(type default)
			)
			(fill yes)
			(layer "F.Fab")
		)
		(pad "1" smd rect
			(at -2.400046 -2.275078)
			(size 0.2286 0.6096)
			(layers "F.Cu" "F.Mask" "F.Paste")
			(net "PVCCD_HV_CPU0_VOS")
		)
		(pad "2" smd rect
			(at -2.400046 -1.82499)
			(size 0.2286 0.6096)
			(layers "F.Cu" "F.Mask" "F.Paste")
			(net "GND")
		)
		(pad "3" smd rect
			(at -2.400046 -1.374902)
			(size 0.2286 0.6096)
			(layers "F.Cu" "F.Mask" "F.Paste")
			(net "PVCCD_HV_CPU0_VDD1")
		)
		(pad "4" smd rect
			(at -2.400046 -0.925068)
			(size 0.2286 0.6096)
			(layers "F.Cu" "F.Mask" "F.Paste")
			(net "PVCCFA_EHV_CPU0_PVCC")
		)
		(pad "5" smd rect
			(at -2.400046 -0.47498)
			(size 0.2286 0.6096)
			(layers "F.Cu" "F.Mask" "F.Paste")
			(net "GND")
		)
		(pad "6" smd rect
			(at -2.400046 -0.024892)
			(size 0.2286 0.6096)
			(layers "F.Cu" "F.Mask" "F.Paste")
			(net "Net_1920")
		)
		(pad "7_9-20_24" smd circle
			(at 0 1.150112)
			(size 0 0)
			(layers "F.Cu" "F.Mask" "F.Paste")
			(net "GND")
		)
		(pad "10_19" smd rect
			(at 0 2.899918)
			(size 0.6096 4.318)
			(layers "F.Cu" "F.Mask" "F.Paste")
			(net "SW_PVCCD_HV_CPU0_SW1")
		)
		(pad "25_29" smd rect
			(at 1.549908 -1.279906 180)
			(size 2.0574 2.3114)
			(layers "F.Cu" "F.Mask" "F.Paste")
			(net "SW_P12V_PVCCINFAON_CPU0_FLT")
		)
		(pad "30" smd rect
			(at 2.05994 -2.899918 270)
			(size 0.2286 0.6096)
			(layers "F.Cu" "F.Mask" "F.Paste")
			(net "SW_P12V_PVCCINFAON_CPU0_FLT")
		)
		(pad "31" smd rect
			(at 1.610106 -2.899918 270)
			(size 0.2286 0.6096)
			(layers "F.Cu" "F.Mask" "F.Paste")
			(net "Net_1919")
		)
		(pad "32" smd rect
			(at 1.160018 -2.899918 270)
			(size 0.2286 0.6096)
			(layers "F.Cu" "F.Mask" "F.Paste")
			(net "SW_PVCCD_HV_CPU0_BOOTR1")
		)
		(pad "33" smd rect
			(at 0.70993 -2.899918 270)
			(size 0.2286 0.6096)
			(layers "F.Cu" "F.Mask" "F.Paste")
			(net "SW_PVCCD_HV_CPU0_BOOT1")
		)
		(pad "34" smd rect
			(at 0.260096 -2.899918 270)
			(size 0.2286 0.6096)
			(layers "F.Cu" "F.Mask" "F.Paste")
			(net "PVCCD_HV_CPU0_APWM1")
		)
		(pad "35" smd rect
			(at -0.189992 -2.899918 270)
			(size 0.2286 0.6096)
			(layers "F.Cu" "F.Mask" "F.Paste")
			(net "PVCCD_HV_CPU0_VDD1")
		)
		(pad "36" smd rect
			(at -0.64008 -2.899918 270)
			(size 0.2286 0.6096)
			(layers "F.Cu" "F.Mask" "F.Paste")
			(net "PVCCD_HV_CPU0_ATSEN")
		)
		(pad "37" smd rect
			(at -1.089914 -2.899918 270)
			(size 0.2286 0.6096)
			(layers "F.Cu" "F.Mask" "F.Paste")
			(net "PVCCD_HV_CPU0_LSET1")
		)
		(pad "38" smd rect
			(at -1.540002 -2.899918 270)
			(size 0.2286 0.6096)
			(layers "F.Cu" "F.Mask" "F.Paste")
			(net "PVCCD_HV_CPU0_ACSP1")
		)
		(pad "39" smd rect
			(at -1.99009 -2.899918 270)
			(size 0.2286 0.6096)
			(layers "F.Cu" "F.Mask" "F.Paste")
			(net "PVCCD_HV_CPU0_VREF")
		)
		(pad "40" smd rect
			(at -0.87503 -1.27508 270)
			(size 1.7526 1.9558)
			(layers "F.Cu" "F.Mask" "F.Paste")
			(net "GND")
		)
		(pad "41" smd rect
			(at -1.525016 0.249936 180)
			(size 0.3048 0.4572)
			(layers "F.Cu" "F.Mask" "F.Paste")
			(net "Net_1921")
		)
	)
)
